FILE_TYPE = CONNECTIVITY;
{Allegro Design Entry HDL 17.4-2019 S026 (4007227) 1/17/2022}
"PAGE_NUMBER" = 72;
0"NC";
1"GND\g";
2"PVDDCR_CPU0_P1\g";
3"GND\g";
4"PVDDCR_CPU0_P1\g";
5"PVDDCR_CPU0_P1\g";
6"GND\g";
7"PVDDCR_CPU0_P1\g";
8"GND\g";
9"PVDDCR_CPU0_P1\g";
10"GND\g";
11"GND\g";
12"PVDDCR_CPU1_P1\g";
13"GND\g";
14"GND\g";
15"PVDDCR_CPU1_P1\g";
16"PVDDCR_CPU1_P1\g";
17"GND\g";
18"PVDDCR_CPU1_P1\g";
19"PVDDCR_CPU1_P1\g";
20"GND\g";
%"Q_CAP"
"1","(-9400,1325)","0","pure_quanta","I1";
;
LOCATION"C2298"
$SEC"1"
CDS_SEC"1"
MATERIAL"X6S"
TOLERANCE"20%"
VALUE"22UF"
VOLTAGE"4V"
PACK_TYPE"C0402"
CDS_LIB"pure_quanta"
PART_NUMBER"CH622KMEB02";
"B"
$PN"2"3;
"A"
$PN"1"2;
%"Q_CAP"
"1","(-8950,2125)","0","pure_quanta","I10";
;
LOCATION"C2303"
$SEC"1"
CDS_SEC"1"
MATERIAL"X6S"
TOLERANCE"20%"
VALUE"22UF"
VOLTAGE"4V"
PACK_TYPE"C0402"
CDS_LIB"pure_quanta"
PART_NUMBER"CH622KMEB02";
"B"
$PN"2"1;
"A"
$PN"1"4;
%"Q_CAP"
"1","(-825,3725)","0","pure_quanta","I100";
;
LOCATION"C2403"
$SEC"1"
CDS_SEC"1"
MATERIAL"X6S"
TOLERANCE"20%"
VALUE"22UF"
VOLTAGE"4V"
PACK_TYPE"C0402"
CDS_LIB"pure_quanta"
PART_NUMBER"CH622KMEB02";
"B"
$PN"2"17;
"A"
$PN"1"16;
%"Q_CAP"
"1","(-3925,4500)","0","pure_quanta","I101";
;
LOCATION"C2362"
$SEC"1"
CDS_SEC"1"
MATERIAL"X6S"
TOLERANCE"20%"
VALUE"22UF"
VOLTAGE"4V"
PACK_TYPE"C0402"
CDS_LIB"pure_quanta"
PART_NUMBER"CH622KMEB02";
"B"
$PN"2"20;
"A"
$PN"1"19;
%"Q_CAP"
"1","(-3475,4500)","0","pure_quanta","I102";
;
LOCATION"C2368"
$SEC"1"
CDS_SEC"1"
MATERIAL"X6S"
TOLERANCE"20%"
VALUE"22UF"
VOLTAGE"4V"
PACK_TYPE"C0402"
CDS_LIB"pure_quanta"
PART_NUMBER"CH622KMEB02";
"B"
$PN"2"20;
"A"
$PN"1"19;
%"Q_CAP"
"1","(-3025,4500)","0","pure_quanta","I103";
;
LOCATION"C2374"
$SEC"1"
CDS_SEC"1"
MATERIAL"X6S"
TOLERANCE"20%"
VALUE"22UF"
VOLTAGE"4V"
PACK_TYPE"C0402"
CDS_LIB"pure_quanta"
PART_NUMBER"CH622KMEB02";
"B"
$PN"2"20;
"A"
$PN"1"19;
%"Q_CAP"
"1","(-2575,4500)","0","pure_quanta","I104";
;
LOCATION"C2380"
$SEC"1"
CDS_SEC"1"
MATERIAL"X6S"
TOLERANCE"20%"
VALUE"22UF"
VOLTAGE"4V"
PACK_TYPE"C0402"
CDS_LIB"pure_quanta"
PART_NUMBER"CH622KMEB02";
"B"
$PN"2"20;
"A"
$PN"1"19;
%"Q_CAP"
"1","(-2125,4500)","0","pure_quanta","I105";
;
LOCATION"C2386"
$SEC"1"
CDS_SEC"1"
MATERIAL"X6S"
TOLERANCE"20%"
VALUE"22UF"
VOLTAGE"4V"
PACK_TYPE"C0402"
CDS_LIB"pure_quanta"
PART_NUMBER"CH622KMEB02";
"B"
$PN"2"20;
"A"
$PN"1"19;
%"Q_CAP"
"1","(-1675,4500)","0","pure_quanta","I106";
;
LOCATION"C2392"
$SEC"1"
CDS_SEC"1"
MATERIAL"X6S"
TOLERANCE"20%"
VALUE"22UF"
VOLTAGE"4V"
PACK_TYPE"C0402"
CDS_LIB"pure_quanta"
PART_NUMBER"CH622KMEB02";
"B"
$PN"2"20;
"A"
$PN"1"19;
%"Q_CAP"
"1","(-1225,4500)","0","pure_quanta","I107";
;
LOCATION"C2397"
$SEC"1"
CDS_SEC"1"
MATERIAL"X6S"
TOLERANCE"20%"
VALUE"22UF"
VOLTAGE"4V"
PACK_TYPE"C0402"
CDS_LIB"pure_quanta"
PART_NUMBER"CH622KMEB02";
"B"
$PN"2"20;
"A"
$PN"1"19;
%"UNIVERSAL_GND"
"1","(-825,4125)","0","pure_quanta_power","I108";
;
CDS_LIB"pure_quanta_power"
HDL_POWER"GND";
"A"20;
%"Q_CAP"
"1","(-825,4500)","0","pure_quanta","I109";
;
LOCATION"C2402"
$SEC"1"
CDS_SEC"1"
MATERIAL"X6S"
TOLERANCE"20%"
VALUE"22UF"
VOLTAGE"4V"
PACK_TYPE"C0402"
CDS_LIB"pure_quanta"
PART_NUMBER"CH622KMEB02";
"B"
$PN"2"20;
"A"
$PN"1"19;
%"Q_CAP"
"1","(-8500,2125)","0","pure_quanta","I11";
;
LOCATION"C2309"
$SEC"1"
CDS_SEC"1"
MATERIAL"X6S"
TOLERANCE"20%"
VALUE"22UF"
VOLTAGE"4V"
PACK_TYPE"C0402"
CDS_LIB"pure_quanta"
PART_NUMBER"CH622KMEB02";
"B"
$PN"2"1;
"A"
$PN"1"4;
%"Q_CAP"
"1","(-4825,4500)","0","pure_quanta","I110";
;
LOCATION"C2350"
$SEC"1"
CDS_SEC"1"
MATERIAL"X6S"
TOLERANCE"20%"
VALUE"22UF"
VOLTAGE"4V"
PACK_TYPE"C0402"
CDS_LIB"pure_quanta"
PART_NUMBER"CH622KMEB02";
"B"
$PN"2"20;
"A"
$PN"1"19;
%"Q_CAP"
"1","(-8950,2925)","0","pure_quanta","I12";
;
LOCATION"C2302"
$SEC"1"
CDS_SEC"1"
MATERIAL"X6S"
TOLERANCE"20%"
VALUE"22UF"
VOLTAGE"4V"
PACK_TYPE"C0402"
CDS_LIB"pure_quanta"
PART_NUMBER"CH622KMEB02";
"B"
$PN"2"6;
"A"
$PN"1"5;
%"Q_CAP"
"1","(-8950,3725)","0","pure_quanta","I13";
;
LOCATION"C2301"
$SEC"1"
CDS_SEC"1"
MATERIAL"X6S"
TOLERANCE"20%"
VALUE"22UF"
VOLTAGE"4V"
PACK_TYPE"C0402"
CDS_LIB"pure_quanta"
PART_NUMBER"CH622KMEB02";
"B"
$PN"2"8;
"A"
$PN"1"7;
%"Q_CAP"
"1","(-8500,2925)","0","pure_quanta","I14";
;
LOCATION"C2308"
$SEC"1"
CDS_SEC"1"
MATERIAL"X6S"
TOLERANCE"20%"
VALUE"22UF"
VOLTAGE"4V"
PACK_TYPE"C0402"
CDS_LIB"pure_quanta"
PART_NUMBER"CH622KMEB02";
"B"
$PN"2"6;
"A"
$PN"1"5;
%"Q_CAP"
"1","(-8500,3725)","0","pure_quanta","I15";
;
LOCATION"C2307"
$SEC"1"
CDS_SEC"1"
MATERIAL"X6S"
TOLERANCE"20%"
VALUE"22UF"
VOLTAGE"4V"
PACK_TYPE"C0402"
CDS_LIB"pure_quanta"
PART_NUMBER"CH622KMEB02";
"B"
$PN"2"8;
"A"
$PN"1"7;
%"UNIVERSAL_POWER"
"1","(-9400,4000)","0","pure_quanta_power","I16";
;
HDL_POWER"PVDDCR_CPU0_P1"
CDS_LIB"pure_quanta_power";
"A"7;
%"Q_CAP"
"1","(-9400,4500)","0","pure_quanta","I17";
;
LOCATION"C2294"
$SEC"1"
CDS_SEC"1"
MATERIAL"X6S"
TOLERANCE"20%"
VALUE"22UF"
VOLTAGE"4V"
PACK_TYPE"C0402"
CDS_LIB"pure_quanta"
PART_NUMBER"CH622KMEB02";
"B"
$PN"2"10;
"A"
$PN"1"9;
%"UNIVERSAL_POWER"
"1","(-9400,4775)","0","pure_quanta_power","I18";
;
HDL_POWER"PVDDCR_CPU0_P1"
CDS_LIB"pure_quanta_power";
"A"9;
%"Q_CAP"
"1","(-8950,4500)","0","pure_quanta","I19";
;
LOCATION"C2300"
$SEC"1"
CDS_SEC"1"
MATERIAL"X6S"
TOLERANCE"20%"
VALUE"22UF"
VOLTAGE"4V"
PACK_TYPE"C0402"
CDS_LIB"pure_quanta"
PART_NUMBER"CH622KMEB02";
"B"
$PN"2"10;
"A"
$PN"1"9;
%"UNIVERSAL_POWER"
"1","(-9400,1600)","0","pure_quanta_power","I2";
;
HDL_POWER"PVDDCR_CPU0_P1"
CDS_LIB"pure_quanta_power";
"A"2;
%"Q_CAP"
"1","(-8500,4500)","0","pure_quanta","I20";
;
LOCATION"C2306"
$SEC"1"
CDS_SEC"1"
MATERIAL"X6S"
TOLERANCE"20%"
VALUE"22UF"
VOLTAGE"4V"
PACK_TYPE"C0402"
CDS_LIB"pure_quanta"
PART_NUMBER"CH622KMEB02";
"B"
$PN"2"10;
"A"
$PN"1"9;
%"Q_CAP"
"1","(-8050,1325)","0","pure_quanta","I21";
;
LOCATION"C2316"
$SEC"1"
CDS_SEC"1"
MATERIAL"X6S"
TOLERANCE"20%"
VALUE"22UF"
VOLTAGE"4V"
PACK_TYPE"C0402"
CDS_LIB"pure_quanta"
PART_NUMBER"CH622KMEB02";
"B"
$PN"2"3;
"A"
$PN"1"2;
%"UNIVERSAL_GND"
"1","(-7600,950)","0","pure_quanta_power","I22";
;
CDS_LIB"pure_quanta_power"
HDL_POWER"GND";
"A"3;
%"Q_CAP"
"1","(-7600,1325)","0","pure_quanta","I23";
;
LOCATION"C2322"
$SEC"1"
CDS_SEC"1"
MATERIAL"X6S"
TOLERANCE"20%"
VALUE"22UF"
VOLTAGE"4V"
PACK_TYPE"C0402"
CDS_LIB"pure_quanta"
PART_NUMBER"CH622KMEB02";
"B"
$PN"2"3;
"A"
$PN"1"2;
%"Q_CAP"
"1","(-8050,2125)","0","pure_quanta","I24";
;
LOCATION"C2315"
$SEC"1"
CDS_SEC"1"
MATERIAL"X6S"
TOLERANCE"20%"
VALUE"22UF"
VOLTAGE"4V"
PACK_TYPE"C0402"
CDS_LIB"pure_quanta"
PART_NUMBER"CH622KMEB02";
"B"
$PN"2"1;
"A"
$PN"1"4;
%"Q_CAP"
"1","(-7600,2125)","0","pure_quanta","I25";
;
LOCATION"C2321"
$SEC"1"
CDS_SEC"1"
MATERIAL"X6S"
TOLERANCE"20%"
VALUE"22UF"
VOLTAGE"4V"
PACK_TYPE"C0402"
CDS_LIB"pure_quanta"
PART_NUMBER"CH622KMEB02";
"B"
$PN"2"1;
"A"
$PN"1"4;
%"Q_CAP"
"1","(-7150,2125)","0","pure_quanta","I26";
;
LOCATION"C2327"
$SEC"1"
CDS_SEC"1"
MATERIAL"X6S"
TOLERANCE"20%"
VALUE"22UF"
VOLTAGE"4V"
PACK_TYPE"C0402"
CDS_LIB"pure_quanta"
PART_NUMBER"CH622KMEB02";
"B"
$PN"2"1;
"A"
$PN"1"4;
%"Q_CAP"
"1","(-8050,2925)","0","pure_quanta","I27";
;
LOCATION"C2314"
$SEC"1"
CDS_SEC"1"
MATERIAL"X6S"
TOLERANCE"20%"
VALUE"22UF"
VOLTAGE"4V"
PACK_TYPE"C0402"
CDS_LIB"pure_quanta"
PART_NUMBER"CH622KMEB02";
"B"
$PN"2"6;
"A"
$PN"1"5;
%"Q_CAP"
"1","(-8050,3725)","0","pure_quanta","I28";
;
LOCATION"C2313"
$SEC"1"
CDS_SEC"1"
MATERIAL"X6S"
TOLERANCE"20%"
VALUE"22UF"
VOLTAGE"4V"
PACK_TYPE"C0402"
CDS_LIB"pure_quanta"
PART_NUMBER"CH622KMEB02";
"B"
$PN"2"8;
"A"
$PN"1"7;
%"Q_CAP"
"1","(-7600,2925)","0","pure_quanta","I29";
;
LOCATION"C2320"
$SEC"1"
CDS_SEC"1"
MATERIAL"X6S"
TOLERANCE"20%"
VALUE"22UF"
VOLTAGE"4V"
PACK_TYPE"C0402"
CDS_LIB"pure_quanta"
PART_NUMBER"CH622KMEB02";
"B"
$PN"2"6;
"A"
$PN"1"5;
%"Q_CAP"
"1","(-8950,1325)","0","pure_quanta","I3";
;
LOCATION"C2304"
$SEC"1"
CDS_SEC"1"
MATERIAL"X6S"
TOLERANCE"20%"
VALUE"22UF"
VOLTAGE"4V"
PACK_TYPE"C0402"
CDS_LIB"pure_quanta"
PART_NUMBER"CH622KMEB02";
"B"
$PN"2"3;
"A"
$PN"1"2;
%"Q_CAP"
"1","(-7150,2925)","0","pure_quanta","I30";
;
LOCATION"C2326"
$SEC"1"
CDS_SEC"1"
MATERIAL"X6S"
TOLERANCE"20%"
VALUE"22UF"
VOLTAGE"4V"
PACK_TYPE"C0402"
CDS_LIB"pure_quanta"
PART_NUMBER"CH622KMEB02";
"B"
$PN"2"6;
"A"
$PN"1"5;
%"Q_CAP"
"1","(-7600,3725)","0","pure_quanta","I31";
;
LOCATION"C2319"
$SEC"1"
CDS_SEC"1"
MATERIAL"X6S"
TOLERANCE"20%"
VALUE"22UF"
VOLTAGE"4V"
PACK_TYPE"C0402"
CDS_LIB"pure_quanta"
PART_NUMBER"CH622KMEB02";
"B"
$PN"2"8;
"A"
$PN"1"7;
%"Q_CAP"
"1","(-7150,3725)","0","pure_quanta","I32";
;
LOCATION"C2325"
$SEC"1"
CDS_SEC"1"
MATERIAL"X6S"
TOLERANCE"20%"
VALUE"22UF"
VOLTAGE"4V"
PACK_TYPE"C0402"
CDS_LIB"pure_quanta"
PART_NUMBER"CH622KMEB02";
"B"
$PN"2"8;
"A"
$PN"1"7;
%"Q_CAP"
"1","(-6700,2125)","0","pure_quanta","I33";
;
LOCATION"C2333"
$SEC"1"
CDS_SEC"1"
MATERIAL"X6S"
TOLERANCE"20%"
VALUE"22UF"
VOLTAGE"4V"
PACK_TYPE"C0402"
CDS_LIB"pure_quanta"
PART_NUMBER"CH622KMEB02";
"B"
$PN"2"1;
"A"
$PN"1"4;
%"Q_CAP"
"1","(-6250,2125)","0","pure_quanta","I34";
;
LOCATION"C2338"
$SEC"1"
CDS_SEC"1"
MATERIAL"X6S"
TOLERANCE"20%"
VALUE"22UF"
VOLTAGE"4V"
PACK_TYPE"C0402"
CDS_LIB"pure_quanta"
PART_NUMBER"CH622KMEB02";
"B"
$PN"2"1;
"A"
$PN"1"4;
%"Q_CAP"
"1","(-6700,2925)","0","pure_quanta","I35";
;
LOCATION"C2332"
$SEC"1"
CDS_SEC"1"
MATERIAL"X6S"
TOLERANCE"20%"
VALUE"22UF"
VOLTAGE"4V"
PACK_TYPE"C0402"
CDS_LIB"pure_quanta"
PART_NUMBER"CH622KMEB02";
"B"
$PN"2"6;
"A"
$PN"1"5;
%"Q_CAP"
"1","(-6700,3725)","0","pure_quanta","I36";
;
LOCATION"C2331"
$SEC"1"
CDS_SEC"1"
MATERIAL"X6S"
TOLERANCE"20%"
VALUE"22UF"
VOLTAGE"4V"
PACK_TYPE"C0402"
CDS_LIB"pure_quanta"
PART_NUMBER"CH622KMEB02";
"B"
$PN"2"8;
"A"
$PN"1"7;
%"Q_CAP"
"1","(-6250,2925)","0","pure_quanta","I37";
;
LOCATION"C2337"
$SEC"1"
CDS_SEC"1"
MATERIAL"X6S"
TOLERANCE"20%"
VALUE"22UF"
VOLTAGE"4V"
PACK_TYPE"C0402"
CDS_LIB"pure_quanta"
PART_NUMBER"CH622KMEB02";
"B"
$PN"2"6;
"A"
$PN"1"5;
%"Q_CAP"
"1","(-6250,3725)","0","pure_quanta","I38";
;
LOCATION"C2336"
$SEC"1"
CDS_SEC"1"
MATERIAL"X6S"
TOLERANCE"20%"
VALUE"22UF"
VOLTAGE"4V"
PACK_TYPE"C0402"
CDS_LIB"pure_quanta"
PART_NUMBER"CH622KMEB02";
"B"
$PN"2"8;
"A"
$PN"1"7;
%"UNIVERSAL_POWER"
"1","(-4825,1600)","0","pure_quanta_power","I39";
;
HDL_POWER"PVDDCR_CPU1_P1"
CDS_LIB"pure_quanta_power";
"A"12;
%"Q_CAP"
"1","(-8500,1325)","0","pure_quanta","I4";
;
LOCATION"C2310"
$SEC"1"
CDS_SEC"1"
MATERIAL"X6S"
TOLERANCE"20%"
VALUE"22UF"
VOLTAGE"4V"
PACK_TYPE"C0402"
CDS_LIB"pure_quanta"
PART_NUMBER"CH622KMEB02";
"B"
$PN"2"3;
"A"
$PN"1"2;
%"Q_CAP"
"1","(-4825,1325)","0","pure_quanta","I40";
;
LOCATION"C2354"
$SEC"1"
CDS_SEC"1"
MATERIAL"X6S"
TOLERANCE"20%"
VALUE"22UF"
VOLTAGE"4V"
PACK_TYPE"C0402"
CDS_LIB"pure_quanta"
PART_NUMBER"CH622KMEB02";
"B"
$PN"2"13;
"A"
$PN"1"12;
%"Q_CAP"
"1","(-4375,1325)","0","pure_quanta","I41";
;
LOCATION"C2360"
$SEC"1"
CDS_SEC"1"
MATERIAL"X6S"
TOLERANCE"20%"
VALUE"22UF"
VOLTAGE"4V"
PACK_TYPE"C0402"
CDS_LIB"pure_quanta"
PART_NUMBER"CH622KMEB02";
"B"
$PN"2"13;
"A"
$PN"1"12;
%"Q_CAP"
"1","(-5800,2125)","0","pure_quanta","I42";
;
LOCATION"C2343"
$SEC"1"
CDS_SEC"1"
MATERIAL"X6S"
TOLERANCE"20%"
VALUE"22UF"
VOLTAGE"4V"
PACK_TYPE"C0402"
CDS_LIB"pure_quanta"
PART_NUMBER"CH622KMEB02";
"B"
$PN"2"1;
"A"
$PN"1"4;
%"UNIVERSAL_GND"
"1","(-5400,1750)","0","pure_quanta_power","I43";
;
CDS_LIB"pure_quanta_power"
HDL_POWER"GND";
"A"1;
%"Q_CAP"
"1","(-5400,2125)","0","pure_quanta","I44";
;
LOCATION"C2348"
$SEC"1"
CDS_SEC"1"
MATERIAL"X6S"
TOLERANCE"20%"
VALUE"22UF"
VOLTAGE"4V"
PACK_TYPE"C0402"
CDS_LIB"pure_quanta"
PART_NUMBER"CH622KMEB02";
"B"
$PN"2"1;
"A"
$PN"1"4;
%"UNIVERSAL_GND"
"1","(-5400,2550)","0","pure_quanta_power","I45";
;
CDS_LIB"pure_quanta_power"
HDL_POWER"GND";
"A"6;
%"Q_CAP"
"1","(-5800,2925)","0","pure_quanta","I46";
;
LOCATION"C2342"
$SEC"1"
CDS_SEC"1"
MATERIAL"X6S"
TOLERANCE"20%"
VALUE"22UF"
VOLTAGE"4V"
PACK_TYPE"C0402"
CDS_LIB"pure_quanta"
PART_NUMBER"CH622KMEB02";
"B"
$PN"2"6;
"A"
$PN"1"5;
%"Q_CAP"
"1","(-5800,3725)","0","pure_quanta","I47";
;
LOCATION"C2341"
$SEC"1"
CDS_SEC"1"
MATERIAL"X6S"
TOLERANCE"20%"
VALUE"22UF"
VOLTAGE"4V"
PACK_TYPE"C0402"
CDS_LIB"pure_quanta"
PART_NUMBER"CH622KMEB02";
"B"
$PN"2"8;
"A"
$PN"1"7;
%"Q_CAP"
"1","(-5400,2925)","0","pure_quanta","I48";
;
LOCATION"C2347"
$SEC"1"
CDS_SEC"1"
MATERIAL"X6S"
TOLERANCE"20%"
VALUE"22UF"
VOLTAGE"4V"
PACK_TYPE"C0402"
CDS_LIB"pure_quanta"
PART_NUMBER"CH622KMEB02";
"B"
$PN"2"6;
"A"
$PN"1"5;
%"UNIVERSAL_GND"
"1","(-5400,3350)","0","pure_quanta_power","I49";
;
CDS_LIB"pure_quanta_power"
HDL_POWER"GND";
"A"8;
%"Q_CAP"
"1","(-9400,2125)","0","pure_quanta","I5";
;
LOCATION"C2297"
$SEC"1"
CDS_SEC"1"
MATERIAL"X6S"
TOLERANCE"20%"
VALUE"22UF"
VOLTAGE"4V"
PACK_TYPE"C0402"
CDS_LIB"pure_quanta"
PART_NUMBER"CH622KMEB02";
"B"
$PN"2"1;
"A"
$PN"1"4;
%"Q_CAP"
"1","(-5400,3725)","0","pure_quanta","I50";
;
LOCATION"C2346"
$SEC"1"
CDS_SEC"1"
MATERIAL"X6S"
TOLERANCE"20%"
VALUE"22UF"
VOLTAGE"4V"
PACK_TYPE"C0402"
CDS_LIB"pure_quanta"
PART_NUMBER"CH622KMEB02";
"B"
$PN"2"8;
"A"
$PN"1"7;
%"Q_CAP"
"1","(-4825,2125)","0","pure_quanta","I51";
;
LOCATION"C2353"
$SEC"1"
CDS_SEC"1"
MATERIAL"X6S"
TOLERANCE"20%"
VALUE"22UF"
VOLTAGE"4V"
PACK_TYPE"C0402"
CDS_LIB"pure_quanta"
PART_NUMBER"CH622KMEB02";
"B"
$PN"2"11;
"A"
$PN"1"15;
%"UNIVERSAL_POWER"
"1","(-4825,2400)","0","pure_quanta_power","I52";
;
HDL_POWER"PVDDCR_CPU1_P1"
CDS_LIB"pure_quanta_power";
"A"15;
%"Q_CAP"
"1","(-4375,2125)","0","pure_quanta","I53";
;
LOCATION"C2359"
$SEC"1"
CDS_SEC"1"
MATERIAL"X6S"
TOLERANCE"20%"
VALUE"22UF"
VOLTAGE"4V"
PACK_TYPE"C0402"
CDS_LIB"pure_quanta"
PART_NUMBER"CH622KMEB02";
"B"
$PN"2"11;
"A"
$PN"1"15;
%"UNIVERSAL_POWER"
"1","(-4825,3200)","0","pure_quanta_power","I54";
;
HDL_POWER"PVDDCR_CPU1_P1"
CDS_LIB"pure_quanta_power";
"A"18;
%"Q_CAP"
"1","(-4825,2925)","0","pure_quanta","I55";
;
LOCATION"C2352"
$SEC"1"
CDS_SEC"1"
MATERIAL"X6S"
TOLERANCE"20%"
VALUE"22UF"
VOLTAGE"4V"
PACK_TYPE"C0402"
CDS_LIB"pure_quanta"
PART_NUMBER"CH622KMEB02";
"B"
$PN"2"14;
"A"
$PN"1"18;
%"Q_CAP"
"1","(-4825,3725)","0","pure_quanta","I56";
;
LOCATION"C2351"
$SEC"1"
CDS_SEC"1"
MATERIAL"X6S"
TOLERANCE"20%"
VALUE"22UF"
VOLTAGE"4V"
PACK_TYPE"C0402"
CDS_LIB"pure_quanta"
PART_NUMBER"CH622KMEB02";
"B"
$PN"2"17;
"A"
$PN"1"16;
%"Q_CAP"
"1","(-4375,2925)","0","pure_quanta","I57";
;
LOCATION"C2358"
$SEC"1"
CDS_SEC"1"
MATERIAL"X6S"
TOLERANCE"20%"
VALUE"22UF"
VOLTAGE"4V"
PACK_TYPE"C0402"
CDS_LIB"pure_quanta"
PART_NUMBER"CH622KMEB02";
"B"
$PN"2"14;
"A"
$PN"1"18;
%"Q_CAP"
"1","(-4375,3725)","0","pure_quanta","I58";
;
LOCATION"C2357"
$SEC"1"
CDS_SEC"1"
MATERIAL"X6S"
TOLERANCE"20%"
VALUE"22UF"
VOLTAGE"4V"
PACK_TYPE"C0402"
CDS_LIB"pure_quanta"
PART_NUMBER"CH622KMEB02";
"B"
$PN"2"17;
"A"
$PN"1"16;
%"Q_CAP"
"1","(-8050,4500)","0","pure_quanta","I59";
;
LOCATION"C2312"
$SEC"1"
CDS_SEC"1"
MATERIAL"X6S"
TOLERANCE"20%"
VALUE"22UF"
VOLTAGE"4V"
PACK_TYPE"C0402"
CDS_LIB"pure_quanta"
PART_NUMBER"CH622KMEB02";
"B"
$PN"2"10;
"A"
$PN"1"9;
%"UNIVERSAL_POWER"
"1","(-9400,2400)","0","pure_quanta_power","I6";
;
HDL_POWER"PVDDCR_CPU0_P1"
CDS_LIB"pure_quanta_power";
"A"4;
%"Q_CAP"
"1","(-7600,4500)","0","pure_quanta","I60";
;
LOCATION"C2318"
$SEC"1"
CDS_SEC"1"
MATERIAL"X6S"
TOLERANCE"20%"
VALUE"22UF"
VOLTAGE"4V"
PACK_TYPE"C0402"
CDS_LIB"pure_quanta"
PART_NUMBER"CH622KMEB02";
"B"
$PN"2"10;
"A"
$PN"1"9;
%"Q_CAP"
"1","(-7150,4500)","0","pure_quanta","I61";
;
LOCATION"C2324"
$SEC"1"
CDS_SEC"1"
MATERIAL"X6S"
TOLERANCE"20%"
VALUE"22UF"
VOLTAGE"4V"
PACK_TYPE"C0402"
CDS_LIB"pure_quanta"
PART_NUMBER"CH622KMEB02";
"B"
$PN"2"10;
"A"
$PN"1"9;
%"Q_CAP"
"1","(-6700,4500)","0","pure_quanta","I62";
;
LOCATION"C2330"
$SEC"1"
CDS_SEC"1"
MATERIAL"X6S"
TOLERANCE"20%"
VALUE"22UF"
VOLTAGE"4V"
PACK_TYPE"C0402"
CDS_LIB"pure_quanta"
PART_NUMBER"CH622KMEB02";
"B"
$PN"2"10;
"A"
$PN"1"9;
%"Q_CAP"
"1","(-6250,4500)","0","pure_quanta","I63";
;
LOCATION"C2335"
$SEC"1"
CDS_SEC"1"
MATERIAL"X6S"
TOLERANCE"20%"
VALUE"22UF"
VOLTAGE"4V"
PACK_TYPE"C0402"
CDS_LIB"pure_quanta"
PART_NUMBER"CH622KMEB02";
"B"
$PN"2"10;
"A"
$PN"1"9;
%"Q_CAP"
"1","(-5800,4500)","0","pure_quanta","I64";
;
LOCATION"C2340"
$SEC"1"
CDS_SEC"1"
MATERIAL"X6S"
TOLERANCE"20%"
VALUE"22UF"
VOLTAGE"4V"
PACK_TYPE"C0402"
CDS_LIB"pure_quanta"
PART_NUMBER"CH622KMEB02";
"B"
$PN"2"10;
"A"
$PN"1"9;
%"UNIVERSAL_GND"
"1","(-5400,4125)","0","pure_quanta_power","I65";
;
CDS_LIB"pure_quanta_power"
HDL_POWER"GND";
"A"10;
%"Q_CAP"
"1","(-5400,4500)","0","pure_quanta","I66";
;
LOCATION"C2345"
$SEC"1"
CDS_SEC"1"
MATERIAL"X6S"
TOLERANCE"20%"
VALUE"22UF"
VOLTAGE"4V"
PACK_TYPE"C0402"
CDS_LIB"pure_quanta"
PART_NUMBER"CH622KMEB02";
"B"
$PN"2"10;
"A"
$PN"1"9;
%"UNIVERSAL_POWER"
"1","(-4825,4000)","0","pure_quanta_power","I67";
;
HDL_POWER"PVDDCR_CPU1_P1"
CDS_LIB"pure_quanta_power";
"A"16;
%"Q_CAP"
"1","(-4375,4500)","0","pure_quanta","I68";
;
LOCATION"C2356"
$SEC"1"
CDS_SEC"1"
MATERIAL"X6S"
TOLERANCE"20%"
VALUE"22UF"
VOLTAGE"4V"
PACK_TYPE"C0402"
CDS_LIB"pure_quanta"
PART_NUMBER"CH622KMEB02";
"B"
$PN"2"20;
"A"
$PN"1"19;
%"UNIVERSAL_POWER"
"1","(-4825,4775)","0","pure_quanta_power","I69";
;
HDL_POWER"PVDDCR_CPU1_P1"
CDS_LIB"pure_quanta_power";
"A"19;
%"Q_CAP"
"1","(-9400,2925)","0","pure_quanta","I7";
;
LOCATION"C2296"
$SEC"1"
CDS_SEC"1"
MATERIAL"X6S"
TOLERANCE"20%"
VALUE"22UF"
VOLTAGE"4V"
PACK_TYPE"C0402"
CDS_LIB"pure_quanta"
PART_NUMBER"CH622KMEB02";
"B"
$PN"2"6;
"A"
$PN"1"5;
%"Q_CAP"
"1","(-3925,1325)","0","pure_quanta","I70";
;
LOCATION"C2366"
$SEC"1"
CDS_SEC"1"
MATERIAL"X6S"
TOLERANCE"20%"
VALUE"22UF"
VOLTAGE"4V"
PACK_TYPE"C0402"
CDS_LIB"pure_quanta"
PART_NUMBER"CH622KMEB02";
"B"
$PN"2"13;
"A"
$PN"1"12;
%"Q_CAP"
"1","(-3475,1325)","0","pure_quanta","I71";
;
LOCATION"C2372"
$SEC"1"
CDS_SEC"1"
MATERIAL"X6S"
TOLERANCE"20%"
VALUE"22UF"
VOLTAGE"4V"
PACK_TYPE"C0402"
CDS_LIB"pure_quanta"
PART_NUMBER"CH622KMEB02";
"B"
$PN"2"13;
"A"
$PN"1"12;
%"Q_CAP"
"1","(-3025,1325)","0","pure_quanta","I72";
;
LOCATION"C2378"
$SEC"1"
CDS_SEC"1"
MATERIAL"X6S"
TOLERANCE"20%"
VALUE"22UF"
VOLTAGE"4V"
PACK_TYPE"C0402"
CDS_LIB"pure_quanta"
PART_NUMBER"CH622KMEB02";
"B"
$PN"2"13;
"A"
$PN"1"12;
%"UNIVERSAL_GND"
"1","(-3025,950)","0","pure_quanta_power","I73";
;
CDS_LIB"pure_quanta_power"
HDL_POWER"GND";
"A"13;
%"Q_CAP"
"1","(-3925,2125)","0","pure_quanta","I74";
;
LOCATION"C2365"
$SEC"1"
CDS_SEC"1"
MATERIAL"X6S"
TOLERANCE"20%"
VALUE"22UF"
VOLTAGE"4V"
PACK_TYPE"C0402"
CDS_LIB"pure_quanta"
PART_NUMBER"CH622KMEB02";
"B"
$PN"2"11;
"A"
$PN"1"15;
%"Q_CAP"
"1","(-3475,2125)","0","pure_quanta","I75";
;
LOCATION"C2371"
$SEC"1"
CDS_SEC"1"
MATERIAL"X6S"
TOLERANCE"20%"
VALUE"22UF"
VOLTAGE"4V"
PACK_TYPE"C0402"
CDS_LIB"pure_quanta"
PART_NUMBER"CH622KMEB02";
"B"
$PN"2"11;
"A"
$PN"1"15;
%"Q_CAP"
"1","(-3925,2925)","0","pure_quanta","I76";
;
LOCATION"C2364"
$SEC"1"
CDS_SEC"1"
MATERIAL"X6S"
TOLERANCE"20%"
VALUE"22UF"
VOLTAGE"4V"
PACK_TYPE"C0402"
CDS_LIB"pure_quanta"
PART_NUMBER"CH622KMEB02";
"B"
$PN"2"14;
"A"
$PN"1"18;
%"Q_CAP"
"1","(-3925,3725)","0","pure_quanta","I77";
;
LOCATION"C2363"
$SEC"1"
CDS_SEC"1"
MATERIAL"X6S"
TOLERANCE"20%"
VALUE"22UF"
VOLTAGE"4V"
PACK_TYPE"C0402"
CDS_LIB"pure_quanta"
PART_NUMBER"CH622KMEB02";
"B"
$PN"2"17;
"A"
$PN"1"16;
%"Q_CAP"
"1","(-3475,2925)","0","pure_quanta","I78";
;
LOCATION"C2370"
$SEC"1"
CDS_SEC"1"
MATERIAL"X6S"
TOLERANCE"20%"
VALUE"22UF"
VOLTAGE"4V"
PACK_TYPE"C0402"
CDS_LIB"pure_quanta"
PART_NUMBER"CH622KMEB02";
"B"
$PN"2"14;
"A"
$PN"1"18;
%"Q_CAP"
"1","(-3475,3725)","0","pure_quanta","I79";
;
LOCATION"C2369"
$SEC"1"
CDS_SEC"1"
MATERIAL"X6S"
TOLERANCE"20%"
VALUE"22UF"
VOLTAGE"4V"
PACK_TYPE"C0402"
CDS_LIB"pure_quanta"
PART_NUMBER"CH622KMEB02";
"B"
$PN"2"17;
"A"
$PN"1"16;
%"UNIVERSAL_POWER"
"1","(-9400,3200)","0","pure_quanta_power","I8";
;
HDL_POWER"PVDDCR_CPU0_P1"
CDS_LIB"pure_quanta_power";
"A"5;
%"Q_CAP"
"1","(-3025,2925)","0","pure_quanta","I80";
;
LOCATION"C2376"
$SEC"1"
CDS_SEC"1"
MATERIAL"X6S"
TOLERANCE"20%"
VALUE"22UF"
VOLTAGE"4V"
PACK_TYPE"C0402"
CDS_LIB"pure_quanta"
PART_NUMBER"CH622KMEB02";
"B"
$PN"2"14;
"A"
$PN"1"18;
%"Q_CAP"
"1","(-3025,2125)","0","pure_quanta","I81";
;
LOCATION"C2377"
$SEC"1"
CDS_SEC"1"
MATERIAL"X6S"
TOLERANCE"20%"
VALUE"22UF"
VOLTAGE"4V"
PACK_TYPE"C0402"
CDS_LIB"pure_quanta"
PART_NUMBER"CH622KMEB02";
"B"
$PN"2"11;
"A"
$PN"1"15;
%"Q_CAP"
"1","(-2575,2125)","0","pure_quanta","I82";
;
LOCATION"C2383"
$SEC"1"
CDS_SEC"1"
MATERIAL"X6S"
TOLERANCE"20%"
VALUE"22UF"
VOLTAGE"4V"
PACK_TYPE"C0402"
CDS_LIB"pure_quanta"
PART_NUMBER"CH622KMEB02";
"B"
$PN"2"11;
"A"
$PN"1"15;
%"Q_CAP"
"1","(-2125,2125)","0","pure_quanta","I83";
;
LOCATION"C2389"
$SEC"1"
CDS_SEC"1"
MATERIAL"X6S"
TOLERANCE"20%"
VALUE"22UF"
VOLTAGE"4V"
PACK_TYPE"C0402"
CDS_LIB"pure_quanta"
PART_NUMBER"CH622KMEB02";
"B"
$PN"2"11;
"A"
$PN"1"15;
%"Q_CAP"
"1","(-2575,2925)","0","pure_quanta","I84";
;
LOCATION"C2382"
$SEC"1"
CDS_SEC"1"
MATERIAL"X6S"
TOLERANCE"20%"
VALUE"22UF"
VOLTAGE"4V"
PACK_TYPE"C0402"
CDS_LIB"pure_quanta"
PART_NUMBER"CH622KMEB02";
"B"
$PN"2"14;
"A"
$PN"1"18;
%"Q_CAP"
"1","(-3025,3725)","0","pure_quanta","I85";
;
LOCATION"C2375"
$SEC"1"
CDS_SEC"1"
MATERIAL"X6S"
TOLERANCE"20%"
VALUE"22UF"
VOLTAGE"4V"
PACK_TYPE"C0402"
CDS_LIB"pure_quanta"
PART_NUMBER"CH622KMEB02";
"B"
$PN"2"17;
"A"
$PN"1"16;
%"Q_CAP"
"1","(-2575,3725)","0","pure_quanta","I86";
;
LOCATION"C2381"
$SEC"1"
CDS_SEC"1"
MATERIAL"X6S"
TOLERANCE"20%"
VALUE"22UF"
VOLTAGE"4V"
PACK_TYPE"C0402"
CDS_LIB"pure_quanta"
PART_NUMBER"CH622KMEB02";
"B"
$PN"2"17;
"A"
$PN"1"16;
%"Q_CAP"
"1","(-2125,2925)","0","pure_quanta","I87";
;
LOCATION"C2388"
$SEC"1"
CDS_SEC"1"
MATERIAL"X6S"
TOLERANCE"20%"
VALUE"22UF"
VOLTAGE"4V"
PACK_TYPE"C0402"
CDS_LIB"pure_quanta"
PART_NUMBER"CH622KMEB02";
"B"
$PN"2"14;
"A"
$PN"1"18;
%"Q_CAP"
"1","(-2125,3725)","0","pure_quanta","I88";
;
LOCATION"C2387"
$SEC"1"
CDS_SEC"1"
MATERIAL"X6S"
TOLERANCE"20%"
VALUE"22UF"
VOLTAGE"4V"
PACK_TYPE"C0402"
CDS_LIB"pure_quanta"
PART_NUMBER"CH622KMEB02";
"B"
$PN"2"17;
"A"
$PN"1"16;
%"Q_CAP"
"1","(-1675,2125)","0","pure_quanta","I89";
;
LOCATION"C2395"
$SEC"1"
CDS_SEC"1"
MATERIAL"X6S"
TOLERANCE"20%"
VALUE"22UF"
VOLTAGE"4V"
PACK_TYPE"C0402"
CDS_LIB"pure_quanta"
PART_NUMBER"CH622KMEB02";
"B"
$PN"2"11;
"A"
$PN"1"15;
%"Q_CAP"
"1","(-9400,3725)","0","pure_quanta","I9";
;
LOCATION"C2295"
$SEC"1"
CDS_SEC"1"
MATERIAL"X6S"
TOLERANCE"20%"
VALUE"22UF"
VOLTAGE"4V"
PACK_TYPE"C0402"
CDS_LIB"pure_quanta"
PART_NUMBER"CH622KMEB02";
"B"
$PN"2"8;
"A"
$PN"1"7;
%"Q_CAP"
"1","(-1225,2125)","0","pure_quanta","I90";
;
LOCATION"C2400"
$SEC"1"
CDS_SEC"1"
MATERIAL"X6S"
TOLERANCE"20%"
VALUE"22UF"
VOLTAGE"4V"
PACK_TYPE"C0402"
CDS_LIB"pure_quanta"
PART_NUMBER"CH622KMEB02";
"B"
$PN"2"11;
"A"
$PN"1"15;
%"Q_CAP"
"1","(-1675,2925)","0","pure_quanta","I91";
;
LOCATION"C2394"
$SEC"1"
CDS_SEC"1"
MATERIAL"X6S"
TOLERANCE"20%"
VALUE"22UF"
VOLTAGE"4V"
PACK_TYPE"C0402"
CDS_LIB"pure_quanta"
PART_NUMBER"CH622KMEB02";
"B"
$PN"2"14;
"A"
$PN"1"18;
%"Q_CAP"
"1","(-1675,3725)","0","pure_quanta","I92";
;
LOCATION"C2393"
$SEC"1"
CDS_SEC"1"
MATERIAL"X6S"
TOLERANCE"20%"
VALUE"22UF"
VOLTAGE"4V"
PACK_TYPE"C0402"
CDS_LIB"pure_quanta"
PART_NUMBER"CH622KMEB02";
"B"
$PN"2"17;
"A"
$PN"1"16;
%"Q_CAP"
"1","(-1225,2925)","0","pure_quanta","I93";
;
LOCATION"C2399"
$SEC"1"
CDS_SEC"1"
MATERIAL"X6S"
TOLERANCE"20%"
VALUE"22UF"
VOLTAGE"4V"
PACK_TYPE"C0402"
CDS_LIB"pure_quanta"
PART_NUMBER"CH622KMEB02";
"B"
$PN"2"14;
"A"
$PN"1"18;
%"Q_CAP"
"1","(-1225,3725)","0","pure_quanta","I94";
;
LOCATION"C2398"
$SEC"1"
CDS_SEC"1"
MATERIAL"X6S"
TOLERANCE"20%"
VALUE"22UF"
VOLTAGE"4V"
PACK_TYPE"C0402"
CDS_LIB"pure_quanta"
PART_NUMBER"CH622KMEB02";
"B"
$PN"2"17;
"A"
$PN"1"16;
%"UNIVERSAL_GND"
"1","(-825,1750)","0","pure_quanta_power","I95";
;
CDS_LIB"pure_quanta_power"
HDL_POWER"GND";
"A"11;
%"Q_CAP"
"1","(-825,2125)","0","pure_quanta","I96";
;
LOCATION"C2405"
$SEC"1"
CDS_SEC"1"
MATERIAL"X6S"
TOLERANCE"20%"
VALUE"22UF"
VOLTAGE"4V"
PACK_TYPE"C0402"
CDS_LIB"pure_quanta"
PART_NUMBER"CH622KMEB02";
"B"
$PN"2"11;
"A"
$PN"1"15;
%"UNIVERSAL_GND"
"1","(-825,2550)","0","pure_quanta_power","I97";
;
CDS_LIB"pure_quanta_power"
HDL_POWER"GND";
"A"14;
%"Q_CAP"
"1","(-825,2925)","0","pure_quanta","I98";
;
LOCATION"C2404"
$SEC"1"
CDS_SEC"1"
MATERIAL"X6S"
TOLERANCE"20%"
VALUE"22UF"
VOLTAGE"4V"
PACK_TYPE"C0402"
CDS_LIB"pure_quanta"
PART_NUMBER"CH622KMEB02";
"B"
$PN"2"14;
"A"
$PN"1"18;
%"UNIVERSAL_GND"
"1","(-825,3350)","0","pure_quanta_power","I99";
;
CDS_LIB"pure_quanta_power"
HDL_POWER"GND";
"A"17;
END.
